(kicad_pcb
	(version 20260206)
	(generator "pcbnew")
	(generator_version "10.0")
	(general
		(thickness 1.6)
		(legacy_teardrops no)
	)
	(paper "A4")
	(title_block
		(title "Wiwynn_Tioga_Pass_MB.brd")
		(comment 1 "Tioga Pass / footprints 1921-1926 of 4770")
	)
	(layers
		(0 "F.Cu" signal "TOP")
		(4 "In1.Cu" signal "L2GND")
		(6 "In2.Cu" signal "L3")
		(8 "In3.Cu" signal "L4GND")
		(10 "In4.Cu" signal "L5")
		(12 "In5.Cu" signal "L6GND")
		(14 "In6.Cu" signal "L7VCC")
		(16 "In7.Cu" signal "L8VCC")
		(18 "In8.Cu" signal "L9GND")
		(20 "In9.Cu" signal "L10")
		(22 "In10.Cu" signal "L11GND")
		(24 "In11.Cu" signal "L12")
		(26 "In12.Cu" signal "L13GND")
		(2 "B.Cu" signal "BOTTOM")
		(9 "F.Adhes" user "F.Adhesive")
		(11 "B.Adhes" user "B.Adhesive")
		(13 "F.Paste" user "Package Geometry/Pastemask Top")
		(15 "B.Paste" user "Package Geometry/Pastemask Bottom")
		(5 "F.SilkS" user "Ref Des/Silkscreen Top")
		(7 "B.SilkS" user "Ref Des/Silkscreen Bottom")
		(1 "F.Mask" user "Board Geometry/Soldermask Top")
		(3 "B.Mask" user "Board Geometry/Soldermask Bottom")
		(17 "Dwgs.User" user "User.Drawings")
		(19 "Cmts.User" user "User.Comments")
		(21 "Eco1.User" user "User.Eco1")
		(23 "Eco2.User" user "User.Eco2")
		(25 "Edge.Cuts" user "Board Geometry/Outline")
		(27 "Margin" user)
		(31 "F.CrtYd" user "Package Geometry/Place Bound Top")
		(29 "B.CrtYd" user "Package Geometry/Place Bound Bottom")
		(35 "F.Fab" user "Ref Des/Assembly Top")
		(33 "B.Fab" user "Ref Des/Assembly Bottom")
	)
	(footprint ""
		(layer "F.Cu")
		(at 466.09 -147.1295)
		(property "Reference" "C9A4"
			(at 0 0 0)
			(layer "F.SilkS")
			(hide yes)
			(effects
				(font
					(size 1.27 1.27)
				)
			)
		)
		(property "Value" ""
			(at 0 0 0)
			(layer "F.Fab")
			(effects
				(font
					(size 1.27 1.27)
				)
			)
		)
		(duplicate_pad_numbers_are_jumpers no)
		(fp_poly
			(pts
				(xy 0.3048 -0.1016) (xy 0.3048 0.9906) (xy -0.3048 0.9906) (xy -0.3048 -0.1016)
			)
			(stroke
				(width 0)
				(type default)
			)
			(fill no)
			(layer "F.CrtYd")
		)
		(fp_line
			(start -0.3048 -0.1016)
			(end -0.3048 0.9906)
			(stroke
				(width 0.1)
				(type default)
			)
			(layer "F.Fab")
		)
		(fp_line
			(start -0.3048 0.9906)
			(end 0.3048 0.9906)
			(stroke
				(width 0.1)
				(type default)
			)
			(layer "F.Fab")
		)
		(fp_line
			(start 0.3048 -0.1016)
			(end -0.3048 -0.1016)
			(stroke
				(width 0.1)
				(type default)
			)
			(layer "F.Fab")
		)
		(fp_line
			(start 0.3048 0.9906)
			(end 0.3048 -0.1016)
			(stroke
				(width 0.1)
				(type default)
			)
			(layer "F.Fab")
		)
		(pad "1" smd rect
			(at 0 0)
			(size 0.508 0.508)
			(layers "F.Cu" "F.Mask" "F.Paste")
			(net "XDP_CPU_PWR_DEBUG_N")
		)
		(pad "2" smd rect
			(at 0 0.889)
			(size 0.508 0.508)
			(layers "F.Cu" "F.Mask" "F.Paste")
			(net "GND")
		)
		(zone
			(layer "F.Cu")
			(hatch none 0.5)
			(connect_pads
				(clearance 0)
			)
			(min_thickness 0.25)
			(keepout
				(tracks allowed)
				(vias not_allowed)
				(pads allowed)
				(copperpour not_allowed)
				(footprints allowed)
			)
			(placement
				(enabled no)
				(sheetname "")
			)
			(fill
				(thermal_gap 0.5)
				(thermal_bridge_width 0.5)
				(island_removal_mode 0)
			)
			(polygon
				(pts
					(xy 465.836 -146.8755) (xy 466.344 -146.8755) (xy 466.344 -146.4945) (xy 465.836 -146.4945)
				)
			)
		)
		(zone
			(layer "F.Cu")
			(hatch none 0.5)
			(connect_pads
				(clearance 0)
			)
			(min_thickness 0.25)
			(keepout
				(tracks not_allowed)
				(vias allowed)
				(pads allowed)
				(copperpour not_allowed)
				(footprints allowed)
			)
			(placement
				(enabled no)
				(sheetname "")
			)
			(fill
				(thermal_gap 0.5)
				(thermal_bridge_width 0.5)
				(island_removal_mode 0)
			)
			(polygon
				(pts
					(xy 465.836 -146.4945) (xy 466.344 -146.4945) (xy 466.344 -146.8755) (xy 465.836 -146.8755)
				)
			)
		)
	)
	(footprint ""
		(layer "F.Cu")
		(at 78.735174 -26.591006 -45)
		(property "Reference" "C2F1"
			(at 0 0 315)
			(layer "F.SilkS")
			(hide yes)
			(effects
				(font
					(size 1.27 1.27)
				)
			)
		)
		(property "Value" ""
			(at 0 0 315)
			(layer "F.Fab")
			(effects
				(font
					(size 1.27 1.27)
				)
			)
		)
		(duplicate_pad_numbers_are_jumpers no)
		(fp_poly
			(pts
				(xy -0.500021 -0.201359) (xy 0.500231 -0.201359) (xy 0.500231 1.598486) (xy -0.500021 1.598486)
			)
			(stroke
				(width 0)
				(type default)
			)
			(fill no)
			(layer "F.CrtYd")
		)
		(fp_line
			(start -0.500021 1.598486)
			(end -0.5002 -0.201337)
			(stroke
				(width 0.1)
				(type default)
			)
			(layer "F.Fab")
		)
		(fp_line
			(start 0.500021 1.598486)
			(end -0.500021 1.598486)
			(stroke
				(width 0.1)
				(type default)
			)
			(layer "F.Fab")
		)
		(fp_line
			(start -0.5002 -0.201337)
			(end 0.5002 -0.201337)
			(stroke
				(width 0.1)
				(type default)
			)
			(layer "F.Fab")
		)
		(fp_line
			(start 0.5002 -0.201337)
			(end 0.500021 1.598486)
			(stroke
				(width 0.1)
				(type default)
			)
			(layer "F.Fab")
		)
		(pad "1" smd rect
			(at 0 0 225)
			(size 0.889 0.9906)
			(layers "F.Cu" "F.Mask" "F.Paste")
			(net "PVDDQ_GHJ")
		)
		(pad "2" smd rect
			(at 0 1.397 225)
			(size 0.889 0.9906)
			(layers "F.Cu" "F.Mask" "F.Paste")
			(net "GND")
		)
		(zone
			(layer "F.Cu")
			(hatch none 0.5)
			(connect_pads
				(clearance 0)
			)
			(min_thickness 0.25)
			(keepout
				(tracks allowed)
				(vias not_allowed)
				(pads allowed)
				(copperpour not_allowed)
				(footprints allowed)
			)
			(placement
				(enabled no)
				(sheetname "")
			)
			(fill
				(thermal_gap 0.5)
				(thermal_bridge_width 0.5)
				(island_removal_mode 0)
			)
			(polygon
				(pts
					(xy 77.7113 -26.267664) (xy 78.41176 -25.567204) (xy 78.77097 -25.926414) (xy 78.07051 -26.626874)
				)
			)
		)
		(zone
			(layer "F.Cu")
			(hatch none 0.5)
			(connect_pads
				(clearance 0)
			)
			(min_thickness 0.25)
			(keepout
				(tracks not_allowed)
				(vias allowed)
				(pads allowed)
				(copperpour not_allowed)
				(footprints allowed)
			)
			(placement
				(enabled no)
				(sheetname "")
			)
			(fill
				(thermal_gap 0.5)
				(thermal_bridge_width 0.5)
				(island_removal_mode 0)
			)
			(polygon
				(pts
					(xy 77.7113 -26.267664) (xy 78.41176 -25.567204) (xy 78.77097 -25.926414) (xy 78.07051 -26.626874)
				)
			)
		)
	)
	(footprint ""
		(layer "F.Cu")
		(at 324.5485 -122.555 90)
		(property "Reference" "C6B8"
			(at -0.8382 -0.67818 90)
			(unlocked yes)
			(layer "F.SilkS")
			(effects
				(font
					(size 0.4064 0.254)
					(thickness 0.1524)
				)
				(justify left)
			)
		)
		(property "Value" ""
			(at 0 0 90)
			(layer "F.Fab")
			(effects
				(font
					(size 1.27 1.27)
				)
			)
		)
		(duplicate_pad_numbers_are_jumpers no)
		(fp_poly
			(pts
				(xy 0.3048 -0.1016) (xy 0.3048 0.9906) (xy -0.3048 0.9906) (xy -0.3048 -0.1016)
			)
			(stroke
				(width 0)
				(type default)
			)
			(fill no)
			(layer "F.CrtYd")
		)
		(fp_line
			(start 0.3048 -0.1016)
			(end -0.3048 -0.1016)
			(stroke
				(width 0.1)
				(type default)
			)
			(layer "F.Fab")
		)
		(fp_line
			(start -0.3048 -0.1016)
			(end -0.3048 0.9906)
			(stroke
				(width 0.1)
				(type default)
			)
			(layer "F.Fab")
		)
		(fp_line
			(start 0.3048 0.9906)
			(end 0.3048 -0.1016)
			(stroke
				(width 0.1)
				(type default)
			)
			(layer "F.Fab")
		)
		(fp_line
			(start -0.3048 0.9906)
			(end 0.3048 0.9906)
			(stroke
				(width 0.1)
				(type default)
			)
			(layer "F.Fab")
		)
		(pad "1" smd rect
			(at 0 0 90)
			(size 0.508 0.508)
			(layers "F.Cu" "F.Mask" "F.Paste")
			(net "P3E_CPU0_PE1_PCH_TXP<14>")
		)
		(pad "2" smd rect
			(at 0 0.889 90)
			(size 0.508 0.508)
			(layers "F.Cu" "F.Mask" "F.Paste")
			(net "P3E_CPU0_PE1_PCH_C_TXP<14>")
		)
		(zone
			(layer "F.Cu")
			(hatch none 0.5)
			(connect_pads
				(clearance 0)
			)
			(min_thickness 0.25)
			(keepout
				(tracks allowed)
				(vias not_allowed)
				(pads allowed)
				(copperpour not_allowed)
				(footprints allowed)
			)
			(placement
				(enabled no)
				(sheetname "")
			)
			(fill
				(thermal_gap 0.5)
				(thermal_bridge_width 0.5)
				(island_removal_mode 0)
			)
			(polygon
				(pts
					(xy 324.8025 -122.301) (xy 324.8025 -122.809) (xy 325.1835 -122.809) (xy 325.1835 -122.301)
				)
			)
		)
		(zone
			(layer "F.Cu")
			(hatch none 0.5)
			(connect_pads
				(clearance 0)
			)
			(min_thickness 0.25)
			(keepout
				(tracks not_allowed)
				(vias allowed)
				(pads allowed)
				(copperpour not_allowed)
				(footprints allowed)
			)
			(placement
				(enabled no)
				(sheetname "")
			)
			(fill
				(thermal_gap 0.5)
				(thermal_bridge_width 0.5)
				(island_removal_mode 0)
			)
			(polygon
				(pts
					(xy 325.1835 -122.301) (xy 325.1835 -122.809) (xy 324.8025 -122.809) (xy 324.8025 -122.301)
				)
			)
		)
	)
	(footprint ""
		(layer "F.Cu")
		(at 387.35 1.651 90)
		(property "Reference" "R7G23"
			(at 0 0 90)
			(layer "F.SilkS")
			(hide yes)
			(effects
				(font
					(size 1.27 1.27)
				)
			)
		)
		(property "Value" ""
			(at 0 0 90)
			(layer "F.Fab")
			(effects
				(font
					(size 1.27 1.27)
				)
			)
		)
		(duplicate_pad_numbers_are_jumpers no)
		(fp_poly
			(pts
				(xy -0.2794 -0.1016) (xy 0.2794 -0.1016) (xy 0.2794 0.9906) (xy -0.2794 0.9906)
			)
			(stroke
				(width 0)
				(type default)
			)
			(fill no)
			(layer "F.CrtYd")
		)
		(fp_line
			(start 0.2794 -0.1016)
			(end -0.2794 -0.1016)
			(stroke
				(width 0.1)
				(type default)
			)
			(layer "F.Fab")
		)
		(fp_line
			(start -0.2794 -0.1016)
			(end -0.2794 0.9906)
			(stroke
				(width 0.1)
				(type default)
			)
			(layer "F.Fab")
		)
		(fp_line
			(start 0.2794 0.9906)
			(end 0.2794 -0.1016)
			(stroke
				(width 0.1)
				(type default)
			)
			(layer "F.Fab")
		)
		(fp_line
			(start -0.2794 0.9906)
			(end 0.2794 0.9906)
			(stroke
				(width 0.1)
				(type default)
			)
			(layer "F.Fab")
		)
		(pad "1" smd rect
			(at 0 0 90)
			(size 0.508 0.508)
			(layers "F.Cu" "F.Mask" "F.Paste")
			(net "P3V3_STBY")
		)
		(pad "2" smd rect
			(at 0 0.889 90)
			(size 0.508 0.508)
			(layers "F.Cu" "F.Mask" "F.Paste")
			(net "JTAG_TDI_R")
		)
		(zone
			(layer "F.Cu")
			(hatch none 0.5)
			(connect_pads
				(clearance 0)
			)
			(min_thickness 0.25)
			(keepout
				(tracks allowed)
				(vias not_allowed)
				(pads allowed)
				(copperpour not_allowed)
				(footprints allowed)
			)
			(placement
				(enabled no)
				(sheetname "")
			)
			(fill
				(thermal_gap 0.5)
				(thermal_bridge_width 0.5)
				(island_removal_mode 0)
			)
			(polygon
				(pts
					(xy 387.604 1.905) (xy 387.604 1.397) (xy 387.985 1.397) (xy 387.985 1.905)
				)
			)
		)
		(zone
			(layer "F.Cu")
			(hatch none 0.5)
			(connect_pads
				(clearance 0)
			)
			(min_thickness 0.25)
			(keepout
				(tracks not_allowed)
				(vias allowed)
				(pads allowed)
				(copperpour not_allowed)
				(footprints allowed)
			)
			(placement
				(enabled no)
				(sheetname "")
			)
			(fill
				(thermal_gap 0.5)
				(thermal_bridge_width 0.5)
				(island_removal_mode 0)
			)
			(polygon
				(pts
					(xy 387.985 1.905) (xy 387.985 1.397) (xy 387.604 1.397) (xy 387.604 1.905)
				)
			)
		)
	)
	(footprint ""
		(layer "F.Cu")
		(at 198.877936 -122.301)
		(property "Reference" "C4B13"
			(at 3.2512 10.18667 0)
			(unlocked yes)
			(layer "F.SilkS")
			(effects
				(font
					(size 0.7874 0.5842)
					(thickness 0.1524)
				)
			)
		)
		(property "Value" ""
			(at 0 0 0)
			(layer "F.Fab")
			(effects
				(font
					(size 1.27 1.27)
				)
			)
		)
		(duplicate_pad_numbers_are_jumpers no)
		(fp_line
			(start -5.1435 -0.127)
			(end -4.3815 -1.016)
			(stroke
				(width 0.1524)
				(type default)
			)
			(layer "F.SilkS")
		)
		(fp_line
			(start -5.1435 9.271)
			(end -5.1435 -0.127)
			(stroke
				(width 0.1524)
				(type default)
			)
			(layer "F.SilkS")
		)
		(fp_line
			(start -4.3815 -1.016)
			(end -1.8415 -1.016)
			(stroke
				(width 0.1524)
				(type default)
			)
			(layer "F.SilkS")
		)
		(fp_line
			(start -1.8415 -2.0955)
			(end -1.8415 2.0955)
			(stroke
				(width 0.1524)
				(type default)
			)
			(layer "F.SilkS")
		)
		(fp_line
			(start -1.8415 2.0955)
			(end -1.4097 2.0955)
			(stroke
				(width 0.1524)
				(type default)
			)
			(layer "F.SilkS")
		)
		(fp_line
			(start -1.4097 -2.0955)
			(end -1.8415 -2.0955)
			(stroke
				(width 0.1524)
				(type default)
			)
			(layer "F.SilkS")
		)
		(fp_line
			(start -1.4097 9.271)
			(end -5.1435 9.271)
			(stroke
				(width 0.1524)
				(type default)
			)
			(layer "F.SilkS")
		)
		(fp_line
			(start 1.4097 -2.0955)
			(end 1.8415 -2.0955)
			(stroke
				(width 0.1524)
				(type default)
			)
			(layer "F.SilkS")
		)
		(fp_line
			(start 1.8415 -2.0955)
			(end 1.8415 2.0955)
			(stroke
				(width 0.1524)
				(type default)
			)
			(layer "F.SilkS")
		)
		(fp_line
			(start 1.8415 -1.016)
			(end 4.3815 -1.016)
			(stroke
				(width 0.1524)
				(type default)
			)
			(layer "F.SilkS")
		)
		(fp_line
			(start 1.8415 2.0955)
			(end 1.4097 2.0955)
			(stroke
				(width 0.1524)
				(type default)
			)
			(layer "F.SilkS")
		)
		(fp_line
			(start 4.3815 -1.016)
			(end 5.1435 -0.127)
			(stroke
				(width 0.1524)
				(type default)
			)
			(layer "F.SilkS")
		)
		(fp_line
			(start 5.1435 -0.127)
			(end 5.1435 9.271)
			(stroke
				(width 0.1524)
				(type default)
			)
			(layer "F.SilkS")
		)
		(fp_line
			(start 5.1435 9.271)
			(end 1.4097 9.271)
			(stroke
				(width 0.1524)
				(type default)
			)
			(layer "F.SilkS")
		)
		(fp_poly
			(pts
				(xy -5.14604 -0.12954) (xy -4.38404 -1.01346) (xy 4.37896 -1.016) (xy 5.1435 -0.12954) (xy 5.14096 9.271)
				(xy -5.14604 9.27354)
			)
			(stroke
				(width 0)
				(type default)
			)
			(fill no)
			(layer "F.CrtYd")
		)
		(fp_line
			(start -5.1435 -0.127)
			(end -4.3815 -1.016)
			(stroke
				(width 0.1)
				(type default)
			)
			(layer "F.Fab")
		)
		(fp_line
			(start -5.1435 9.271)
			(end -5.1435 -0.127)
			(stroke
				(width 0.1)
				(type default)
			)
			(layer "F.Fab")
		)
		(fp_line
			(start -4.3815 -1.016)
			(end 4.3815 -1.016)
			(stroke
				(width 0.1)
				(type default)
			)
			(layer "F.Fab")
		)
		(fp_line
			(start 4.3815 -1.016)
			(end 5.1435 -0.127)
			(stroke
				(width 0.1)
				(type default)
			)
			(layer "F.Fab")
		)
		(fp_line
			(start 5.1435 -0.127)
			(end 5.1435 9.271)
			(stroke
				(width 0.1)
				(type default)
			)
			(layer "F.Fab")
		)
		(fp_line
			(start 5.1435 9.271)
			(end -5.1435 9.271)
			(stroke
				(width 0.1)
				(type default)
			)
			(layer "F.Fab")
		)
		(fp_circle
			(center 0 4.1275)
			(end 4.9911 4.1275)
			(stroke
				(width 0.1)
				(type default)
			)
			(fill no)
			(layer "F.Fab")
		)
		(pad "1" smd rect
			(at 0 0)
			(size 1.905 4.191)
			(layers "F.Cu" "F.Mask" "F.Paste")
			(net "P12V_STBY")
		)
		(pad "2" smd rect
			(at 0 8.255)
			(size 1.905 4.191)
			(layers "F.Cu" "F.Mask" "F.Paste")
			(net "GND")
		)
		(zone
			(layer "F.Cu")
			(hatch none 0.5)
			(connect_pads
				(clearance 0)
			)
			(min_thickness 0.25)
			(keepout
				(tracks allowed)
				(vias not_allowed)
				(pads allowed)
				(copperpour not_allowed)
				(footprints allowed)
			)
			(placement
				(enabled no)
				(sheetname "")
			)
			(fill
				(thermal_gap 0.5)
				(thermal_bridge_width 0.5)
				(island_removal_mode 0)
			)
			(polygon
				(pts
					(xy 193.734436 -113.03) (xy 204.021436 -113.03) (xy 204.021436 -122.428) (xy 203.259436 -123.317)
					(xy 194.496436 -123.317) (xy 193.734436 -122.428)
				)
			)
		)
	)
	(footprint ""
		(layer "F.Cu")
		(at 110.70844 -73.318116)
		(property "Reference" "C3D19"
			(at 0 0 0)
			(layer "F.SilkS")
			(hide yes)
			(effects
				(font
					(size 1.27 1.27)
				)
			)
		)
		(property "Value" ""
			(at 0 0 0)
			(layer "F.Fab")
			(effects
				(font
					(size 1.27 1.27)
				)
			)
		)
		(duplicate_pad_numbers_are_jumpers no)
		(fp_poly
			(pts
				(xy -0.4953 -0.2032) (xy 0.4953 -0.2032) (xy 0.4953 1.6002) (xy -0.4953 1.6002)
			)
			(stroke
				(width 0)
				(type default)
			)
			(fill no)
			(layer "F.CrtYd")
		)
		(fp_line
			(start -0.4953 -0.2032)
			(end 0.4953 -0.2032)
			(stroke
				(width 0.1)
				(type default)
			)
			(layer "F.Fab")
		)
		(fp_line
			(start -0.4953 1.6002)
			(end -0.4953 -0.2032)
			(stroke
				(width 0.1)
				(type default)
			)
			(layer "F.Fab")
		)
		(fp_line
			(start 0.4953 -0.2032)
			(end 0.4953 1.6002)
			(stroke
				(width 0.1)
				(type default)
			)
			(layer "F.Fab")
		)
		(fp_line
			(start 0.4953 1.6002)
			(end -0.4953 1.6002)
			(stroke
				(width 0.1)
				(type default)
			)
			(layer "F.Fab")
		)
		(pad "1" smd rect
			(at 0 0)
			(size 0.762 0.889)
			(layers "F.Cu" "F.Mask" "F.Paste")
			(net "PVCCMCP_CPU1")
		)
		(pad "2" smd rect
			(at 0 1.397)
			(size 0.762 0.889)
			(layers "F.Cu" "F.Mask" "F.Paste")
			(net "GND")
		)
		(zone
			(layer "F.Cu")
			(hatch none 0.5)
			(connect_pads
				(clearance 0)
			)
			(min_thickness 0.25)
			(keepout
				(tracks not_allowed)
				(vias allowed)
				(pads allowed)
				(copperpour not_allowed)
				(footprints allowed)
			)
			(placement
				(enabled no)
				(sheetname "")
			)
			(fill
				(thermal_gap 0.5)
				(thermal_bridge_width 0.5)
				(island_removal_mode 0)
			)
			(polygon
				(pts
					(xy 110.32744 -72.873616) (xy 111.08944 -72.873616) (xy 111.08944 -72.365616) (xy 110.32744 -72.365616)
				)
			)
		)
	)
)
